# BASEBOARD_FAB2 (Tioga Pass) — schematic netlist excerpt (pin names and nets, part order shuffled) for the footprints in the layout excerpt that follows; sources: Cadence DE-HDL packaged netlist, KiCad conversion of Wiwynn_Tioga_Pass_MB.brd

R1D3  RES  0.0 5% CHIP  pkg 0402  page 206 : A = SVID_VALERT_VCCIN_CPU1 ; B = SVID_ALERT0_CPU1_R_N
R4G3  RES  1.00K 1% CHIP  pkg 0402  page 98 : A = M_B_VREF ; B = GND
C4B3  CAP  47UF 4V 20% X6S  pkg 0805  page 234 : A = PVPP_KLM ; B = GND

(kicad_pcb
	(version 20260206)
	(generator "pcbnew")
	(generator_version "10.0")
	(general
		(thickness 1.6)
		(legacy_teardrops no)
	)
	(paper "A4")
	(title_block
		(title "Wiwynn_Tioga_Pass_MB.brd")
		(comment 1 "Tioga Pass / footprints 895-897 of 4770")
	)
	(layers
		(0 "F.Cu" signal "TOP")
		(4 "In1.Cu" signal "L2GND")
		(6 "In2.Cu" signal "L3")
		(8 "In3.Cu" signal "L4GND")
		(10 "In4.Cu" signal "L5")
		(12 "In5.Cu" signal "L6GND")
		(14 "In6.Cu" signal "L7VCC")
		(16 "In7.Cu" signal "L8VCC")
		(18 "In8.Cu" signal "L9GND")
		(20 "In9.Cu" signal "L10")
		(22 "In10.Cu" signal "L11GND")
		(24 "In11.Cu" signal "L12")
		(26 "In12.Cu" signal "L13GND")
		(2 "B.Cu" signal "BOTTOM")
		(9 "F.Adhes" user "F.Adhesive")
		(11 "B.Adhes" user "B.Adhesive")
		(13 "F.Paste" user "Package Geometry/Pastemask Top")
		(15 "B.Paste" user "Package Geometry/Pastemask Bottom")
		(5 "F.SilkS" user "Ref Des/Silkscreen Top")
		(7 "B.SilkS" user "Ref Des/Silkscreen Bottom")
		(1 "F.Mask" user "Board Geometry/Soldermask Top")
		(3 "B.Mask" user "Board Geometry/Soldermask Bottom")
		(17 "Dwgs.User" user "User.Drawings")
		(19 "Cmts.User" user "User.Comments")
		(21 "Eco1.User" user "User.Eco1")
		(23 "Eco2.User" user "User.Eco2")
		(25 "Edge.Cuts" user "Board Geometry/Outline")
		(27 "Margin" user)
		(31 "F.CrtYd" user "Package Geometry/Place Bound Top")
		(29 "B.CrtYd" user "Package Geometry/Place Bound Bottom")
		(35 "F.Fab" user "Ref Des/Assembly Top")
		(33 "B.Fab" user "Ref Des/Assembly Bottom")
	)
	(footprint ""
		(layer "F.Cu")
		(at 194.564 -12.5095 180)
		(property "Reference" "R4G3"
			(at 0 0 180)
			(layer "F.SilkS")
			(hide yes)
			(effects
				(font
					(size 1.27 1.27)
				)
			)
		)
		(property "Value" ""
			(at 0 0 180)
			(layer "F.Fab")
			(effects
				(font
					(size 1.27 1.27)
				)
			)
		)
		(duplicate_pad_numbers_are_jumpers no)
		(fp_poly
			(pts
				(xy -0.2794 -0.1016) (xy 0.2794 -0.1016) (xy 0.2794 0.9906) (xy -0.2794 0.9906)
			)
			(stroke
				(width 0)
				(type default)
			)
			(fill no)
			(layer "F.CrtYd")
		)
		(fp_line
			(start 0.2794 0.9906)
			(end 0.2794 -0.1016)
			(stroke
				(width 0.1)
				(type default)
			)
			(layer "F.Fab")
		)
		(fp_line
			(start 0.2794 -0.1016)
			(end -0.2794 -0.1016)
			(stroke
				(width 0.1)
				(type default)
			)
			(layer "F.Fab")
		)
		(fp_line
			(start -0.2794 0.9906)
			(end 0.2794 0.9906)
			(stroke
				(width 0.1)
				(type default)
			)
			(layer "F.Fab")
		)
		(fp_line
			(start -0.2794 -0.1016)
			(end -0.2794 0.9906)
			(stroke
				(width 0.1)
				(type default)
			)
			(layer "F.Fab")
		)
		(pad "1" smd rect
			(at 0 0 180)
			(size 0.508 0.508)
			(layers "F.Cu" "F.Mask" "F.Paste")
			(net "M_B_VREF")
		)
		(pad "2" smd rect
			(at 0 0.889 180)
			(size 0.508 0.508)
			(layers "F.Cu" "F.Mask" "F.Paste")
			(net "GND")
		)
		(zone
			(layer "F.Cu")
			(hatch none 0.5)
			(connect_pads
				(clearance 0)
			)
			(min_thickness 0.25)
			(keepout
				(tracks not_allowed)
				(vias allowed)
				(pads allowed)
				(copperpour not_allowed)
				(footprints allowed)
			)
			(placement
				(enabled no)
				(sheetname "")
			)
			(fill
				(thermal_gap 0.5)
				(thermal_bridge_width 0.5)
				(island_removal_mode 0)
			)
			(polygon
				(pts
					(xy 194.818 -13.1445) (xy 194.31 -13.1445) (xy 194.31 -12.7635) (xy 194.818 -12.7635)
				)
			)
		)
		(zone
			(layer "F.Cu")
			(hatch none 0.5)
			(connect_pads
				(clearance 0)
			)
			(min_thickness 0.25)
			(keepout
				(tracks allowed)
				(vias not_allowed)
				(pads allowed)
				(copperpour not_allowed)
				(footprints allowed)
			)
			(placement
				(enabled no)
				(sheetname "")
			)
			(fill
				(thermal_gap 0.5)
				(thermal_bridge_width 0.5)
				(island_removal_mode 0)
			)
			(polygon
				(pts
					(xy 194.818 -12.7635) (xy 194.31 -12.7635) (xy 194.31 -13.1445) (xy 194.818 -13.1445)
				)
			)
		)
	)
	(footprint ""
		(layer "F.Cu")
		(at 167.6273 -133.1976)
		(property "Reference" "C4B3"
			(at 0 0 0)
			(layer "F.SilkS")
			(hide yes)
			(effects
				(font
					(size 1.27 1.27)
				)
			)
		)
		(property "Value" ""
			(at 0 0 0)
			(layer "F.Fab")
			(effects
				(font
					(size 1.27 1.27)
				)
			)
		)
		(duplicate_pad_numbers_are_jumpers no)
		(fp_poly
			(pts
				(xy -0.7239 -0.2159) (xy 0.7239 -0.2159) (xy 0.7239 1.9939) (xy -0.7239 1.9939)
			)
			(stroke
				(width 0)
				(type default)
			)
			(fill no)
			(layer "F.CrtYd")
		)
		(fp_line
			(start -0.7239 -0.2159)
			(end -0.7239 1.9939)
			(stroke
				(width 0.1)
				(type default)
			)
			(layer "F.Fab")
		)
		(fp_line
			(start -0.7239 1.9939)
			(end 0.7239 1.9939)
			(stroke
				(width 0.1)
				(type default)
			)
			(layer "F.Fab")
		)
		(fp_line
			(start 0.7239 -0.2159)
			(end -0.7239 -0.2159)
			(stroke
				(width 0.1)
				(type default)
			)
			(layer "F.Fab")
		)
		(fp_line
			(start 0.7239 1.9939)
			(end 0.7239 -0.2159)
			(stroke
				(width 0.1)
				(type default)
			)
			(layer "F.Fab")
		)
		(pad "1" smd rect
			(at 0 0)
			(size 1.27 1.016)
			(layers "F.Cu" "F.Mask" "F.Paste")
			(net "PVPP_KLM")
		)
		(pad "2" smd rect
			(at 0 1.778)
			(size 1.27 1.016)
			(layers "F.Cu" "F.Mask" "F.Paste")
			(net "GND")
		)
		(zone
			(layer "F.Cu")
			(hatch none 0.5)
			(connect_pads
				(clearance 0)
			)
			(min_thickness 0.25)
			(keepout
				(tracks not_allowed)
				(vias allowed)
				(pads allowed)
				(copperpour not_allowed)
				(footprints allowed)
			)
			(placement
				(enabled no)
				(sheetname "")
			)
			(fill
				(thermal_gap 0.5)
				(thermal_bridge_width 0.5)
				(island_removal_mode 0)
			)
			(polygon
				(pts
					(xy 166.9923 -132.6896) (xy 168.2623 -132.6896) (xy 168.2623 -131.9276) (xy 166.9923 -131.9276)
				)
			)
		)
	)
	(footprint ""
		(layer "F.Cu")
		(at 19.05 -87.63)
		(property "Reference" "R1D3"
			(at 0 0 0)
			(layer "F.SilkS")
			(hide yes)
			(effects
				(font
					(size 1.27 1.27)
				)
			)
		)
		(property "Value" ""
			(at 0 0 0)
			(layer "F.Fab")
			(effects
				(font
					(size 1.27 1.27)
				)
			)
		)
		(duplicate_pad_numbers_are_jumpers no)
		(fp_rect
			(start -0.2794 0.9906)
			(end 0.2794 -0.1016)
			(stroke
				(width 0)
				(type default)
			)
			(fill no)
			(layer "F.CrtYd")
		)
		(fp_line
			(start -0.2794 -0.1016)
			(end -0.2794 0.9906)
			(stroke
				(width 0.1)
				(type default)
			)
			(layer "F.Fab")
		)
		(fp_line
			(start -0.2794 0.9906)
			(end 0.2794 0.9906)
			(stroke
				(width 0.1)
				(type default)
			)
			(layer "F.Fab")
		)
		(fp_line
			(start 0.2794 -0.1016)
			(end -0.2794 -0.1016)
			(stroke
				(width 0.1)
				(type default)
			)
			(layer "F.Fab")
		)
		(fp_line
			(start 0.2794 0.9906)
			(end 0.2794 -0.1016)
			(stroke
				(width 0.1)
				(type default)
			)
			(layer "F.Fab")
		)
		(pad "1" smd rect
			(at 0 0)
			(size 0.508 0.508)
			(layers "F.Cu" "F.Mask" "F.Paste")
			(net "SVID_VALERT_VCCIN_CPU1")
		)
		(pad "2" smd rect
			(at 0 0.889)
			(size 0.508 0.508)
			(layers "F.Cu" "F.Mask" "F.Paste")
			(net "SVID_ALERT0_CPU1_R_N")
		)
		(zone
			(layer "F.Cu")
			(hatch none 0.5)
			(connect_pads
				(clearance 0)
			)
			(min_thickness 0.25)
			(keepout
				(tracks not_allowed)
				(vias allowed)
				(pads allowed)
				(copperpour not_allowed)
				(footprints allowed)
			)
			(placement
				(enabled no)
				(sheetname "")
			)
			(fill
				(thermal_gap 0.5)
				(thermal_bridge_width 0.5)
				(island_removal_mode 0)
			)
			(polygon
				(pts
					(xy 18.796 -86.995) (xy 19.304 -86.995) (xy 19.304 -87.376) (xy 18.796 -87.376)
				)
			)
		)
		(zone
			(layer "F.Cu")
			(hatch none 0.5)
			(connect_pads
				(clearance 0)
			)
			(min_thickness 0.25)
			(keepout
				(tracks allowed)
				(vias not_allowed)
				(pads allowed)
				(copperpour not_allowed)
				(footprints allowed)
			)
			(placement
				(enabled no)
				(sheetname "")
			)
			(fill
				(thermal_gap 0.5)
				(thermal_bridge_width 0.5)
				(island_removal_mode 0)
			)
			(polygon
				(pts
					(xy 18.796 -86.995) (xy 19.304 -86.995) (xy 19.304 -87.376) (xy 18.796 -87.376)
				)
			)
		)
	)
)
